(kicad_pcb
	(version 20260206)
	(generator "pcbnew")
	(generator_version "10.0")
	(general
		(thickness 1.6)
		(legacy_teardrops no)
	)
	(paper "A4")
	(title_block
		(title "03242023_DA0F0TMBIJ0_F0T_Motherboard_J_brd_V01_OCP.brd")
		(comment 1 "Grand Teton / footprints 5380-5386 of 6105")
	)
	(layers
		(0 "F.Cu" signal "TOP")
		(4 "In1.Cu" signal "GND")
		(6 "In2.Cu" signal "IN1")
		(8 "In3.Cu" signal "GND1")
		(10 "In4.Cu" signal "IN2")
		(12 "In5.Cu" signal "GND2")
		(14 "In6.Cu" signal "IN3")
		(16 "In7.Cu" signal "GND3")
		(18 "In8.Cu" signal "VCC")
		(20 "In9.Cu" signal "VCC1")
		(22 "In10.Cu" signal "GND4")
		(24 "In11.Cu" signal "IN4")
		(26 "In12.Cu" signal "GND5")
		(28 "In13.Cu" signal "IN5")
		(30 "In14.Cu" signal "GND6")
		(32 "In15.Cu" signal "IN6")
		(34 "In16.Cu" signal "GND7")
		(2 "B.Cu" signal "BOTTOM")
		(9 "F.Adhes" user "F.Adhesive")
		(11 "B.Adhes" user "B.Adhesive")
		(13 "F.Paste" user "Package Geometry/Pastemask Top")
		(15 "B.Paste" user "Package Geometry/Pastemask Bottom")
		(5 "F.SilkS" user "Ref Des/Silkscreen Top")
		(7 "B.SilkS" user "Ref Des/Silkscreen Bottom")
		(1 "F.Mask" user "Board Geometry/Soldermask Top")
		(3 "B.Mask" user "Board Geometry/Soldermask Bottom")
		(17 "Dwgs.User" user "User.Drawings")
		(19 "Cmts.User" user "User.Comments")
		(21 "Eco1.User" user "User.Eco1")
		(23 "Eco2.User" user "User.Eco2")
		(25 "Edge.Cuts" user "Board Geometry/Outline")
		(27 "Margin" user)
		(31 "F.CrtYd" user "Package Geometry/Place Bound Top")
		(29 "B.CrtYd" user "Package Geometry/Place Bound Bottom")
		(35 "F.Fab" user "Ref Des/Assembly Top")
		(33 "B.Fab" user "Ref Des/Assembly Bottom")
	)
	(footprint ""
		(layer "B.Cu")
		(at 382.28778 -345.463114 -90)
		(property "Reference" "PR136"
			(at 0 0 90)
			(layer "B.SilkS")
			(hide yes)
			(effects
				(font
					(size 1.27 1.27)
				)
				(justify mirror)
			)
		)
		(property "Value" ""
			(at 0 0 90)
			(layer "B.Fab")
			(effects
				(font
					(size 1.27 1.27)
				)
				(justify mirror)
			)
		)
		(duplicate_pad_numbers_are_jumpers no)
		(fp_line
			(start -0.7874 0.4064)
			(end 0.7874 0.4064)
			(stroke
				(width 0.1524)
				(type default)
			)
			(layer "B.SilkS")
		)
		(fp_line
			(start 0.7874 0.4064)
			(end 0.7874 -0.4064)
			(stroke
				(width 0.1524)
				(type default)
			)
			(layer "B.SilkS")
		)
		(fp_line
			(start -0.7874 -0.4064)
			(end -0.7874 0.4064)
			(stroke
				(width 0.1524)
				(type default)
			)
			(layer "B.SilkS")
		)
		(fp_line
			(start 0.7874 -0.4064)
			(end -0.7874 -0.4064)
			(stroke
				(width 0.1524)
				(type default)
			)
			(layer "B.SilkS")
		)
		(fp_line
			(start -0.67945 0.3048)
			(end -0.120396 0.3048)
			(stroke
				(width 0.1)
				(type default)
			)
			(layer "B.Fab")
		)
		(fp_line
			(start -0.120396 0.3048)
			(end -0.120396 0.2794)
			(stroke
				(width 0.1)
				(type default)
			)
			(layer "B.Fab")
		)
		(fp_line
			(start 0.12065 0.3048)
			(end 0.67945 0.3048)
			(stroke
				(width 0.1)
				(type default)
			)
			(layer "B.Fab")
		)
		(fp_line
			(start 0.67945 0.3048)
			(end 0.67945 -0.305054)
			(stroke
				(width 0.1)
				(type default)
			)
			(layer "B.Fab")
		)
		(fp_line
			(start -0.120396 0.2794)
			(end 0.12065 0.2794)
			(stroke
				(width 0.1)
				(type default)
			)
			(layer "B.Fab")
		)
		(fp_line
			(start 0.12065 0.2794)
			(end 0.12065 0.3048)
			(stroke
				(width 0.1)
				(type default)
			)
			(layer "B.Fab")
		)
		(fp_line
			(start -0.12065 -0.2794)
			(end -0.12065 -0.3048)
			(stroke
				(width 0.1)
				(type default)
			)
			(layer "B.Fab")
		)
		(fp_line
			(start 0.12065 -0.2794)
			(end -0.12065 -0.2794)
			(stroke
				(width 0.1)
				(type default)
			)
			(layer "B.Fab")
		)
		(fp_line
			(start -0.67945 -0.3048)
			(end -0.67945 0.3048)
			(stroke
				(width 0.1)
				(type default)
			)
			(layer "B.Fab")
		)
		(fp_line
			(start -0.12065 -0.3048)
			(end -0.67945 -0.3048)
			(stroke
				(width 0.1)
				(type default)
			)
			(layer "B.Fab")
		)
		(fp_line
			(start 0.12065 -0.305054)
			(end 0.12065 -0.2794)
			(stroke
				(width 0.1)
				(type default)
			)
			(layer "B.Fab")
		)
		(fp_line
			(start 0.67945 -0.305054)
			(end 0.12065 -0.305054)
			(stroke
				(width 0.1)
				(type default)
			)
			(layer "B.Fab")
		)
		(pad "1" smd circle
			(at 0.40005 0 90)
			(size 0 0)
			(layers "B.Cu" "B.Mask" "B.Paste")
			(net "PVCCIN_CPU0_VOS8")
		)
		(pad "2" smd circle
			(at -0.40005 0 90)
			(size 0 0)
			(layers "B.Cu" "B.Mask" "B.Paste")
			(net "PVCCIN_CPU0")
		)
	)
	(footprint ""
		(layer "B.Cu")
		(at 176.10074 -192.699894 -90)
		(property "Reference" "R258"
			(at 0 0 90)
			(layer "B.SilkS")
			(hide yes)
			(effects
				(font
					(size 1.27 1.27)
				)
				(justify mirror)
			)
		)
		(property "Value" ""
			(at 0 0 90)
			(layer "B.Fab")
			(effects
				(font
					(size 1.27 1.27)
				)
				(justify mirror)
			)
		)
		(duplicate_pad_numbers_are_jumpers no)
		(fp_line
			(start -0.7874 0.4064)
			(end 0.7874 0.4064)
			(stroke
				(width 0.1524)
				(type default)
			)
			(layer "B.SilkS")
		)
		(fp_line
			(start 0.7874 0.4064)
			(end 0.7874 -0.4064)
			(stroke
				(width 0.1524)
				(type default)
			)
			(layer "B.SilkS")
		)
		(fp_line
			(start -0.7874 -0.4064)
			(end -0.7874 0.4064)
			(stroke
				(width 0.1524)
				(type default)
			)
			(layer "B.SilkS")
		)
		(fp_line
			(start 0.7874 -0.4064)
			(end -0.7874 -0.4064)
			(stroke
				(width 0.1524)
				(type default)
			)
			(layer "B.SilkS")
		)
		(fp_line
			(start -0.67945 0.3048)
			(end -0.120396 0.3048)
			(stroke
				(width 0.1)
				(type default)
			)
			(layer "B.Fab")
		)
		(fp_line
			(start -0.120396 0.3048)
			(end -0.120396 0.2794)
			(stroke
				(width 0.1)
				(type default)
			)
			(layer "B.Fab")
		)
		(fp_line
			(start 0.12065 0.3048)
			(end 0.67945 0.3048)
			(stroke
				(width 0.1)
				(type default)
			)
			(layer "B.Fab")
		)
		(fp_line
			(start 0.67945 0.3048)
			(end 0.67945 -0.305054)
			(stroke
				(width 0.1)
				(type default)
			)
			(layer "B.Fab")
		)
		(fp_line
			(start -0.120396 0.2794)
			(end 0.12065 0.2794)
			(stroke
				(width 0.1)
				(type default)
			)
			(layer "B.Fab")
		)
		(fp_line
			(start 0.12065 0.2794)
			(end 0.12065 0.3048)
			(stroke
				(width 0.1)
				(type default)
			)
			(layer "B.Fab")
		)
		(fp_line
			(start -0.12065 -0.2794)
			(end -0.12065 -0.3048)
			(stroke
				(width 0.1)
				(type default)
			)
			(layer "B.Fab")
		)
		(fp_line
			(start 0.12065 -0.2794)
			(end -0.12065 -0.2794)
			(stroke
				(width 0.1)
				(type default)
			)
			(layer "B.Fab")
		)
		(fp_line
			(start -0.67945 -0.3048)
			(end -0.67945 0.3048)
			(stroke
				(width 0.1)
				(type default)
			)
			(layer "B.Fab")
		)
		(fp_line
			(start -0.12065 -0.3048)
			(end -0.67945 -0.3048)
			(stroke
				(width 0.1)
				(type default)
			)
			(layer "B.Fab")
		)
		(fp_line
			(start 0.12065 -0.305054)
			(end 0.12065 -0.2794)
			(stroke
				(width 0.1)
				(type default)
			)
			(layer "B.Fab")
		)
		(fp_line
			(start 0.67945 -0.305054)
			(end 0.12065 -0.305054)
			(stroke
				(width 0.1)
				(type default)
			)
			(layer "B.Fab")
		)
		(pad "1" smd circle
			(at 0.40005 0 90)
			(size 0 0)
			(layers "B.Cu" "B.Mask" "B.Paste")
			(net "PVNN_TERM_CPU1")
		)
		(pad "2" smd circle
			(at -0.40005 0 90)
			(size 0 0)
			(layers "B.Cu" "B.Mask" "B.Paste")
			(net "PUD_PCH_BOOT_MODE_CPU1")
		)
	)
	(footprint ""
		(layer "B.Cu")
		(at 122.600974 -333.73568 90)
		(property "Reference" "PC537_P1_4"
			(at 0 0 90)
			(layer "B.SilkS")
			(hide yes)
			(effects
				(font
					(size 1.27 1.27)
				)
				(justify mirror)
			)
		)
		(property "Value" ""
			(at 0 0 90)
			(layer "B.Fab")
			(effects
				(font
					(size 1.27 1.27)
				)
				(justify mirror)
			)
		)
		(duplicate_pad_numbers_are_jumpers no)
		(fp_line
			(start 1.524 -0.762)
			(end -1.524 -0.762)
			(stroke
				(width 0.1524)
				(type default)
			)
			(layer "B.SilkS")
		)
		(fp_line
			(start -1.524 -0.762)
			(end -1.524 0.762)
			(stroke
				(width 0.1524)
				(type default)
			)
			(layer "B.SilkS")
		)
		(fp_line
			(start 1.524 0.762)
			(end 1.524 -0.762)
			(stroke
				(width 0.1524)
				(type default)
			)
			(layer "B.SilkS")
		)
		(fp_line
			(start -1.524 0.762)
			(end 1.524 0.762)
			(stroke
				(width 0.1524)
				(type default)
			)
			(layer "B.SilkS")
		)
		(fp_line
			(start 1.1049 -0.724916)
			(end 1.1049 0.724916)
			(stroke
				(width 0.1)
				(type default)
			)
			(layer "B.Fab")
		)
		(fp_line
			(start -1.1049 -0.724916)
			(end 1.1049 -0.724916)
			(stroke
				(width 0.1)
				(type default)
			)
			(layer "B.Fab")
		)
		(fp_line
			(start 1.1049 0.724916)
			(end -1.1049 0.724916)
			(stroke
				(width 0.1)
				(type default)
			)
			(layer "B.Fab")
		)
		(fp_line
			(start -1.1049 0.724916)
			(end -1.1049 -0.724916)
			(stroke
				(width 0.1)
				(type default)
			)
			(layer "B.Fab")
		)
		(pad "1" smd rect
			(at 0.889 0 90)
			(size 1.016 1.27)
			(layers "B.Cu" "B.Mask" "B.Paste")
			(net "SW_P12V_PVCCIN_CPU1_FLT")
		)
		(pad "2" smd rect
			(at -0.889 0 90)
			(size 1.016 1.27)
			(layers "B.Cu" "B.Mask" "B.Paste")
			(net "GND")
		)
	)
	(footprint ""
		(layer "B.Cu")
		(at 144.51711 -28.989528 180)
		(property "Reference" "C2321"
			(at 0 0 0)
			(layer "B.SilkS")
			(hide yes)
			(effects
				(font
					(size 1.27 1.27)
				)
				(justify mirror)
			)
		)
		(property "Value" ""
			(at 0 0 0)
			(layer "B.Fab")
			(effects
				(font
					(size 1.27 1.27)
				)
				(justify mirror)
			)
		)
		(duplicate_pad_numbers_are_jumpers no)
		(fp_line
			(start 0.7874 0.4064)
			(end 0.7874 -0.4064)
			(stroke
				(width 0.1524)
				(type default)
			)
			(layer "B.SilkS")
		)
		(fp_line
			(start 0.7874 -0.4064)
			(end -0.7874 -0.4064)
			(stroke
				(width 0.1524)
				(type default)
			)
			(layer "B.SilkS")
		)
		(fp_line
			(start -0.7874 0.4064)
			(end 0.7874 0.4064)
			(stroke
				(width 0.1524)
				(type default)
			)
			(layer "B.SilkS")
		)
		(fp_line
			(start -0.7874 -0.4064)
			(end -0.7874 0.4064)
			(stroke
				(width 0.1524)
				(type default)
			)
			(layer "B.SilkS")
		)
		(fp_line
			(start 0.67945 0.3048)
			(end 0.67945 -0.305054)
			(stroke
				(width 0.1)
				(type default)
			)
			(layer "B.Fab")
		)
		(fp_line
			(start 0.67945 -0.305054)
			(end 0.12065 -0.305054)
			(stroke
				(width 0.1)
				(type default)
			)
			(layer "B.Fab")
		)
		(fp_line
			(start 0.12065 0.3048)
			(end 0.67945 0.3048)
			(stroke
				(width 0.1)
				(type default)
			)
			(layer "B.Fab")
		)
		(fp_line
			(start 0.12065 0.2794)
			(end 0.12065 0.3048)
			(stroke
				(width 0.1)
				(type default)
			)
			(layer "B.Fab")
		)
		(fp_line
			(start 0.12065 -0.2794)
			(end -0.12065 -0.2794)
			(stroke
				(width 0.1)
				(type default)
			)
			(layer "B.Fab")
		)
		(fp_line
			(start 0.12065 -0.305054)
			(end 0.12065 -0.2794)
			(stroke
				(width 0.1)
				(type default)
			)
			(layer "B.Fab")
		)
		(fp_line
			(start -0.120396 0.3048)
			(end -0.120396 0.2794)
			(stroke
				(width 0.1)
				(type default)
			)
			(layer "B.Fab")
		)
		(fp_line
			(start -0.120396 0.2794)
			(end 0.12065 0.2794)
			(stroke
				(width 0.1)
				(type default)
			)
			(layer "B.Fab")
		)
		(fp_line
			(start -0.12065 -0.2794)
			(end -0.12065 -0.3048)
			(stroke
				(width 0.1)
				(type default)
			)
			(layer "B.Fab")
		)
		(fp_line
			(start -0.12065 -0.3048)
			(end -0.67945 -0.3048)
			(stroke
				(width 0.1)
				(type default)
			)
			(layer "B.Fab")
		)
		(fp_line
			(start -0.67945 0.3048)
			(end -0.120396 0.3048)
			(stroke
				(width 0.1)
				(type default)
			)
			(layer "B.Fab")
		)
		(fp_line
			(start -0.67945 -0.3048)
			(end -0.67945 0.3048)
			(stroke
				(width 0.1)
				(type default)
			)
			(layer "B.Fab")
		)
		(pad "1" smd circle
			(at 0.40005 0)
			(size 0 0)
			(layers "B.Cu" "B.Mask" "B.Paste")
			(net "PD_USB_HUB_2_RSTN")
		)
		(pad "2" smd circle
			(at -0.40005 0)
			(size 0 0)
			(layers "B.Cu" "B.Mask" "B.Paste")
			(net "GND")
		)
	)
	(footprint ""
		(layer "B.Cu")
		(at 70.369684 -190.744856 90)
		(property "Reference" "R57"
			(at 0 0 90)
			(layer "B.SilkS")
			(hide yes)
			(effects
				(font
					(size 1.27 1.27)
				)
				(justify mirror)
			)
		)
		(property "Value" ""
			(at 0 0 90)
			(layer "B.Fab")
			(effects
				(font
					(size 1.27 1.27)
				)
				(justify mirror)
			)
		)
		(duplicate_pad_numbers_are_jumpers no)
		(fp_line
			(start 0.7874 -0.4064)
			(end -0.7874 -0.4064)
			(stroke
				(width 0.1524)
				(type default)
			)
			(layer "B.SilkS")
		)
		(fp_line
			(start -0.7874 -0.4064)
			(end -0.7874 0.4064)
			(stroke
				(width 0.1524)
				(type default)
			)
			(layer "B.SilkS")
		)
		(fp_line
			(start 0.7874 0.4064)
			(end 0.7874 -0.4064)
			(stroke
				(width 0.1524)
				(type default)
			)
			(layer "B.SilkS")
		)
		(fp_line
			(start -0.7874 0.4064)
			(end 0.7874 0.4064)
			(stroke
				(width 0.1524)
				(type default)
			)
			(layer "B.SilkS")
		)
		(fp_line
			(start 0.67945 -0.305054)
			(end 0.12065 -0.305054)
			(stroke
				(width 0.1)
				(type default)
			)
			(layer "B.Fab")
		)
		(fp_line
			(start 0.12065 -0.305054)
			(end 0.12065 -0.2794)
			(stroke
				(width 0.1)
				(type default)
			)
			(layer "B.Fab")
		)
		(fp_line
			(start -0.12065 -0.3048)
			(end -0.67945 -0.3048)
			(stroke
				(width 0.1)
				(type default)
			)
			(layer "B.Fab")
		)
		(fp_line
			(start -0.67945 -0.3048)
			(end -0.67945 0.3048)
			(stroke
				(width 0.1)
				(type default)
			)
			(layer "B.Fab")
		)
		(fp_line
			(start 0.12065 -0.2794)
			(end -0.12065 -0.2794)
			(stroke
				(width 0.1)
				(type default)
			)
			(layer "B.Fab")
		)
		(fp_line
			(start -0.12065 -0.2794)
			(end -0.12065 -0.3048)
			(stroke
				(width 0.1)
				(type default)
			)
			(layer "B.Fab")
		)
		(fp_line
			(start 0.12065 0.2794)
			(end 0.12065 0.3048)
			(stroke
				(width 0.1)
				(type default)
			)
			(layer "B.Fab")
		)
		(fp_line
			(start -0.120396 0.2794)
			(end 0.12065 0.2794)
			(stroke
				(width 0.1)
				(type default)
			)
			(layer "B.Fab")
		)
		(fp_line
			(start 0.67945 0.3048)
			(end 0.67945 -0.305054)
			(stroke
				(width 0.1)
				(type default)
			)
			(layer "B.Fab")
		)
		(fp_line
			(start 0.12065 0.3048)
			(end 0.67945 0.3048)
			(stroke
				(width 0.1)
				(type default)
			)
			(layer "B.Fab")
		)
		(fp_line
			(start -0.120396 0.3048)
			(end -0.120396 0.2794)
			(stroke
				(width 0.1)
				(type default)
			)
			(layer "B.Fab")
		)
		(fp_line
			(start -0.67945 0.3048)
			(end -0.120396 0.3048)
			(stroke
				(width 0.1)
				(type default)
			)
			(layer "B.Fab")
		)
		(pad "1" smd circle
			(at 0.40005 0 270)
			(size 0 0)
			(layers "B.Cu" "B.Mask" "B.Paste")
			(net "SVID_ALERT0_CPU1_N")
		)
		(pad "2" smd circle
			(at -0.40005 0 270)
			(size 0 0)
			(layers "B.Cu" "B.Mask" "B.Paste")
			(net "SVID_ALERT0_CPU1_R_N")
		)
	)
	(footprint ""
		(layer "B.Cu")
		(at 175.355758 -113.77549 180)
		(property "Reference" "C1929"
			(at 0 0 0)
			(layer "B.SilkS")
			(hide yes)
			(effects
				(font
					(size 1.27 1.27)
				)
				(justify mirror)
			)
		)
		(property "Value" ""
			(at 0 0 0)
			(layer "B.Fab")
			(effects
				(font
					(size 1.27 1.27)
				)
				(justify mirror)
			)
		)
		(duplicate_pad_numbers_are_jumpers no)
		(fp_line
			(start 0.69215 0.2921)
			(end 0.69215 -0.2921)
			(stroke
				(width 0.1524)
				(type default)
			)
			(layer "B.SilkS")
		)
		(fp_line
			(start 0.69215 -0.2921)
			(end -0.69215 -0.2921)
			(stroke
				(width 0.1524)
				(type default)
			)
			(layer "B.SilkS")
		)
		(fp_line
			(start -0.69215 0.2921)
			(end 0.69215 0.2921)
			(stroke
				(width 0.1524)
				(type default)
			)
			(layer "B.SilkS")
		)
		(fp_line
			(start -0.69215 -0.2921)
			(end -0.69215 0.2921)
			(stroke
				(width 0.1524)
				(type default)
			)
			(layer "B.SilkS")
		)
		(fp_line
			(start 0.51435 0.2794)
			(end 0.51435 -0.2794)
			(stroke
				(width 0.1)
				(type default)
			)
			(layer "B.Fab")
		)
		(fp_line
			(start 0.51435 -0.2794)
			(end -0.51435 -0.2794)
			(stroke
				(width 0.1)
				(type default)
			)
			(layer "B.Fab")
		)
		(fp_line
			(start -0.51435 0.2794)
			(end 0.51435 0.2794)
			(stroke
				(width 0.1)
				(type default)
			)
			(layer "B.Fab")
		)
		(fp_line
			(start -0.51435 -0.2794)
			(end -0.51435 0.2794)
			(stroke
				(width 0.1)
				(type default)
			)
			(layer "B.Fab")
		)
		(pad "1" smd circle
			(at 0.40005 0)
			(size 0 0)
			(layers "B.Cu" "B.Mask" "B.Paste")
			(net "P3V3_AUX_FPGA_VCCIO0")
		)
		(pad "2" smd circle
			(at -0.40005 0)
			(size 0 0)
			(layers "B.Cu" "B.Mask" "B.Paste")
			(net "GND")
		)
		(zone
			(layer "B.Cu")
			(hatch none 0.5)
			(connect_pads
				(clearance 0)
			)
			(min_thickness 0.25)
			(keepout
				(tracks not_allowed)
				(vias allowed)
				(pads allowed)
				(copperpour not_allowed)
				(footprints allowed)
			)
			(placement
				(enabled no)
				(sheetname "")
			)
			(fill
				(thermal_gap 0.5)
				(thermal_bridge_width 0.5)
				(island_removal_mode 0)
			)
			(polygon
				(pts
					(xy 175.165258 -113.86312) (xy 175.256698 -113.921286) (xy 175.456088 -113.921286) (xy 175.546258 -113.86312)
					(xy 175.546258 -113.68786) (xy 175.456088 -113.62944) (xy 175.256698 -113.62944) (xy 175.165258 -113.687606)
				)
			)
		)
	)
	(footprint ""
		(layer "B.Cu")
		(at 263.398 -74.933048 90)
		(property "Reference" "PR338"
			(at 0 0 90)
			(layer "B.SilkS")
			(hide yes)
			(effects
				(font
					(size 1.27 1.27)
				)
				(justify mirror)
			)
		)
		(property "Value" ""
			(at 0 0 90)
			(layer "B.Fab")
			(effects
				(font
					(size 1.27 1.27)
				)
				(justify mirror)
			)
		)
		(duplicate_pad_numbers_are_jumpers no)
		(fp_line
			(start 0.7874 -0.4064)
			(end -0.7874 -0.4064)
			(stroke
				(width 0.1524)
				(type default)
			)
			(layer "B.SilkS")
		)
		(fp_line
			(start -0.7874 -0.4064)
			(end -0.7874 0.4064)
			(stroke
				(width 0.1524)
				(type default)
			)
			(layer "B.SilkS")
		)
		(fp_line
			(start 0.7874 0.4064)
			(end 0.7874 -0.4064)
			(stroke
				(width 0.1524)
				(type default)
			)
			(layer "B.SilkS")
		)
		(fp_line
			(start -0.7874 0.4064)
			(end 0.7874 0.4064)
			(stroke
				(width 0.1524)
				(type default)
			)
			(layer "B.SilkS")
		)
		(fp_line
			(start 0.67945 -0.305054)
			(end 0.12065 -0.305054)
			(stroke
				(width 0.1)
				(type default)
			)
			(layer "B.Fab")
		)
		(fp_line
			(start 0.12065 -0.305054)
			(end 0.12065 -0.2794)
			(stroke
				(width 0.1)
				(type default)
			)
			(layer "B.Fab")
		)
		(fp_line
			(start -0.12065 -0.3048)
			(end -0.67945 -0.3048)
			(stroke
				(width 0.1)
				(type default)
			)
			(layer "B.Fab")
		)
		(fp_line
			(start -0.67945 -0.3048)
			(end -0.67945 0.3048)
			(stroke
				(width 0.1)
				(type default)
			)
			(layer "B.Fab")
		)
		(fp_line
			(start 0.12065 -0.2794)
			(end -0.12065 -0.2794)
			(stroke
				(width 0.1)
				(type default)
			)
			(layer "B.Fab")
		)
		(fp_line
			(start -0.12065 -0.2794)
			(end -0.12065 -0.3048)
			(stroke
				(width 0.1)
				(type default)
			)
			(layer "B.Fab")
		)
		(fp_line
			(start 0.12065 0.2794)
			(end 0.12065 0.3048)
			(stroke
				(width 0.1)
				(type default)
			)
			(layer "B.Fab")
		)
		(fp_line
			(start -0.120396 0.2794)
			(end 0.12065 0.2794)
			(stroke
				(width 0.1)
				(type default)
			)
			(layer "B.Fab")
		)
		(fp_line
			(start 0.67945 0.3048)
			(end 0.67945 -0.305054)
			(stroke
				(width 0.1)
				(type default)
			)
			(layer "B.Fab")
		)
		(fp_line
			(start 0.12065 0.3048)
			(end 0.67945 0.3048)
			(stroke
				(width 0.1)
				(type default)
			)
			(layer "B.Fab")
		)
		(fp_line
			(start -0.120396 0.3048)
			(end -0.120396 0.2794)
			(stroke
				(width 0.1)
				(type default)
			)
			(layer "B.Fab")
		)
		(fp_line
			(start -0.67945 0.3048)
			(end -0.120396 0.3048)
			(stroke
				(width 0.1)
				(type default)
			)
			(layer "B.Fab")
		)
		(pad "1" smd circle
			(at 0.40005 0 270)
			(size 0 0)
			(layers "B.Cu" "B.Mask" "B.Paste")
			(net "P1V05_PCH_AUX_MODE")
		)
		(pad "2" smd circle
			(at -0.40005 0 270)
			(size 0 0)
			(layers "B.Cu" "B.Mask" "B.Paste")
			(net "GND")
		)
	)
)
